(kicad_pcb
	(version 20241229)
	(generator "pcbnew")
	(generator_version "9.0")
	(general
		(thickness 1.6296)
		(legacy_teardrops no)
	)
	(paper "A3")
	(title_block
		(title "Thunderbolt to 10GbE adapter")
		(date "2026-04-21")
		(rev "1.1.0")
		(company "Antmicro Ltd")
		(comment 1 "www.antmicro.com")
		(comment 9 "footprints 285-287 of 703")
	)
	(layers
		(0 "F.Cu" signal)
		(4 "In1.Cu" signal)
		(6 "In2.Cu" signal)
		(8 "In3.Cu" signal)
		(10 "In4.Cu" signal)
		(12 "In5.Cu" signal)
		(14 "In6.Cu" signal)
		(2 "B.Cu" signal)
		(9 "F.Adhes" user "F.Adhesive")
		(11 "B.Adhes" user "B.Adhesive")
		(13 "F.Paste" user)
		(15 "B.Paste" user)
		(5 "F.SilkS" user "F.Silkscreen")
		(7 "B.SilkS" user "B.Silkscreen")
		(1 "F.Mask" user)
		(3 "B.Mask" user)
		(17 "Dwgs.User" user "User.Drawings")
		(19 "Cmts.User" user "User.Comments")
		(21 "Eco1.User" user "User.Eco1")
		(23 "Eco2.User" user "User.Eco2")
		(25 "Edge.Cuts" user)
		(27 "Margin" user)
		(31 "F.CrtYd" user "F.Courtyard")
		(29 "B.CrtYd" user "B.Courtyard")
		(35 "F.Fab" user)
		(33 "B.Fab" user)
	)
	(footprint "antmicro-footprints:LED_0603_1608Metric_G"
		(layer "F.Cu")
		(at 183.2 70)
		(descr "LED SMD 0603 Green")
		(tags "LED SMD 0603 Green")
		(property "Reference" "D6"
			(at -1.2 7.75 0)
			(layer "F.SilkS")
			(effects
				(font
					(size 0.7 0.7)
					(thickness 0.15)
				)
				(justify left bottom)
			)
		)
		(property "Value" "LED_G_0603_LG_L29K-G2J1-24-Z"
			(at -0.001 1.599 0)
			(layer "F.Fab")
			(effects
				(font
					(size 0.7 0.7)
					(thickness 0.15)
				)
				(justify left bottom)
			)
		)
		(property "Datasheet" "https://look.ams-osram.com/m/19ee86b3ae0ee95b/original/LG-L29K.pdf"
			(at 0 0 0)
			(layer "F.Fab")
			(hide yes)
			(effects
				(font
					(size 1.27 1.27)
					(thickness 0.15)
				)
			)
		)
		(property "Description" "LED, Green, SMD, 0603, 20 mA, 1.7 V, 570 nm"
			(at 0 0 0)
			(layer "F.Fab")
			(hide yes)
			(effects
				(font
					(size 1.27 1.27)
					(thickness 0.15)
				)
			)
		)
		(property "MPN" "LG L29K-G2J1-24-Z"
			(at 0 0 0)
			(unlocked yes)
			(layer "F.Fab")
			(hide yes)
			(effects
				(font
					(size 1 1)
					(thickness 0.15)
				)
			)
		)
		(property "Manufacturer" "OSRAM"
			(at 0 0 0)
			(unlocked yes)
			(layer "F.Fab")
			(hide yes)
			(effects
				(font
					(size 1 1)
					(thickness 0.15)
				)
			)
		)
		(property "Color" "Green"
			(at 0 0 0)
			(unlocked yes)
			(layer "F.Fab")
			(hide yes)
			(effects
				(font
					(size 1 1)
					(thickness 0.15)
				)
			)
		)
		(property "Author" "Antmicro"
			(at 0 0 0)
			(unlocked yes)
			(layer "F.Fab")
			(hide yes)
			(effects
				(font
					(size 1 1)
					(thickness 0.15)
				)
			)
		)
		(property "License" "Apache-2.0"
			(at 0 0 0)
			(unlocked yes)
			(layer "F.Fab")
			(hide yes)
			(effects
				(font
					(size 1 1)
					(thickness 0.15)
				)
			)
		)
		(sheetname "/X710 DCDC converters/")
		(sheetfile "DCDC_converters_X710.kicad_sch")
		(attr smd)
		(fp_line
			(start -1.18 -0.319)
			(end -1.18 0.321)
			(stroke
				(width 0.15)
				(type solid)
			)
			(layer "F.SilkS")
		)
		(fp_line
			(start -0.094672 0.001008)
			(end -0.24 0.001008)
			(stroke
				(width 0.1)
				(type solid)
			)
			(layer "F.SilkS")
		)
		(fp_line
			(start -0.094672 0.001008)
			(end 0.105328 -0.198992)
			(stroke
				(width 0.1)
				(type solid)
			)
			(layer "F.SilkS")
		)
		(fp_line
			(start -0.094672 0.201008)
			(end -0.094672 -0.198992)
			(stroke
				(width 0.1)
				(type solid)
			)
			(layer "F.SilkS")
		)
		(fp_line
			(start 0.105328 0.001008)
			(end 0.24 0.001)
			(stroke
				(width 0.1)
				(type solid)
			)
			(layer "F.SilkS")
		)
		(fp_line
			(start 0.105328 0.201008)
			(end -0.094672 0.001008)
			(stroke
				(width 0.1)
				(type solid)
			)
			(layer "F.SilkS")
		)
		(fp_line
			(start 0.105328 0.201008)
			(end 0.105328 -0.198992)
			(stroke
				(width 0.1)
				(type solid)
			)
			(layer "F.SilkS")
		)
		(fp_line
			(start 0.22 -0.35)
			(end -0.22 -0.35)
			(stroke
				(width 0.15)
				(type solid)
			)
			(layer "F.SilkS")
		)
		(fp_line
			(start 0.22 0.35)
			(end -0.22 0.35)
			(stroke
				(width 0.15)
				(type solid)
			)
			(layer "F.SilkS")
		)
		(fp_rect
			(start 1.25 0.65)
			(end -1.25 -0.65)
			(stroke
				(width 0.05)
				(type solid)
			)
			(fill no)
			(layer "F.CrtYd")
		)
		(fp_line
			(start -0.199 -0.202)
			(end -0.199 0.1)
			(stroke
				(width 0.15)
				(type solid)
			)
			(layer "F.Fab")
		)
		(fp_line
			(start -0.199 0)
			(end -0.597 0)
			(stroke
				(width 0.15)
				(type solid)
			)
			(layer "F.Fab")
		)
		(fp_line
			(start -0.199 0.2)
			(end -0.199 0.1)
			(stroke
				(width 0.15)
				(type solid)
			)
			(layer "F.Fab")
		)
		(fp_line
			(start -0.101 0)
			(end 0.201 0.2)
			(stroke
				(width 0.15)
				(type solid)
			)
			(layer "F.Fab")
		)
		(fp_line
			(start 0.201 -0.202)
			(end -0.101 0)
			(stroke
				(width 0.15)
				(type solid)
			)
			(layer "F.Fab")
		)
		(fp_line
			(start 0.201 0)
			(end 0.201 -0.202)
			(stroke
				(width 0.15)
				(type solid)
			)
			(layer "F.Fab")
		)
		(fp_line
			(start 0.201 0.2)
			(end 0.201 0)
			(stroke
				(width 0.15)
				(type solid)
			)
			(layer "F.Fab")
		)
		(fp_line
			(start 0.599 0)
			(end 0.201 0)
			(stroke
				(width 0.15)
				(type solid)
			)
			(layer "F.Fab")
		)
		(fp_rect
			(start 0.848 0.4)
			(end -0.85 -0.402)
			(stroke
				(width 0.15)
				(type solid)
			)
			(fill no)
			(layer "F.Fab")
		)
		(fp_text user "${REFERENCE}"
			(at -1.4224 5.999 0)
			(layer "F.Fab")
			(effects
				(font
					(size 0.7 0.7)
					(thickness 0.15)
				)
				(justify left bottom)
			)
		)
		(fp_text user "Author: Antmicro"
			(at -1.4224 4.799 0)
			(layer "F.Fab")
			(effects
				(font
					(size 0.7 0.7)
					(thickness 0.15)
				)
				(justify left bottom)
			)
		)
		(fp_text user "License: Apache-2.0"
			(at -1.4224 3.599 0)
			(layer "F.Fab")
			(effects
				(font
					(size 0.7 0.7)
					(thickness 0.15)
				)
				(justify left bottom)
			)
		)
		(pad "1" smd roundrect
			(at -0.7 0 180)
			(size 0.8 1)
			(layers "F.Cu" "F.Mask" "F.Paste")
			(roundrect_rratio 0.2)
			(net 414 "Net-(D6-C)")
			(pinfunction "C")
			(pintype "passive")
		)
		(pad "2" smd roundrect
			(at 0.7 0 180)
			(size 0.8 1)
			(layers "F.Cu" "F.Mask" "F.Paste")
			(roundrect_rratio 0.2)
			(net 334 "/X710 DCDC converters/+3V3_OUT")
			(pinfunction "A")
			(pintype "passive")
		)
	)
	(footprint "antmicro-footprints:Fiducial_1mm_Mask2mm"
		(layer "F.Cu")
		(at 179 129)
		(descr "Circular Fiducial, 1mm bare copper, 3mm soldermask opening")
		(tags "fiducial")
		(property "Reference" "FD7"
			(at 1.5 0.5 0)
			(layer "F.SilkS")
			(effects
				(font
					(size 0.7 0.7)
					(thickness 0.15)
				)
				(justify left bottom)
			)
		)
		(property "Value" "Fiducial_1mm_Mask2mm"
			(at 0 2.2 0)
			(layer "F.Fab")
			(effects
				(font
					(size 0.7 0.7)
					(thickness 0.15)
				)
				(justify left bottom)
			)
		)
		(property "Description" "Fiducial mask"
			(at 0 0 0)
			(layer "F.Fab")
			(hide yes)
			(effects
				(font
					(size 1.27 1.27)
					(thickness 0.15)
				)
			)
		)
		(property "Author" "Antmicro"
			(at 0 0 0)
			(unlocked yes)
			(layer "F.Fab")
			(hide yes)
			(effects
				(font
					(size 1 1)
					(thickness 0.15)
				)
			)
		)
		(property "License" "Apache-2.0"
			(at 0 0 0)
			(unlocked yes)
			(layer "F.Fab")
			(hide yes)
			(effects
				(font
					(size 1 1)
					(thickness 0.15)
				)
			)
		)
		(sheetname "/")
		(sheetfile "thunderbolt-to-10gbe-adapter.kicad_sch")
		(attr exclude_from_pos_files exclude_from_bom)
		(fp_circle
			(center 0 0)
			(end 1.24 0)
			(stroke
				(width 0.05)
				(type solid)
			)
			(fill no)
			(layer "F.CrtYd")
		)
		(fp_circle
			(center 0 0)
			(end 0.999 0)
			(stroke
				(width 0.15)
				(type solid)
			)
			(fill no)
			(layer "F.Fab")
		)
		(fp_text user "${REFERENCE}"
			(at -1.25 4.603 0)
			(layer "F.Fab")
			(effects
				(font
					(size 0.7 0.7)
					(thickness 0.15)
				)
				(justify left bottom)
			)
		)
		(fp_text user "Author: Antmicro"
			(at -1.25 5.803 0)
			(layer "F.Fab")
			(effects
				(font
					(size 0.7 0.7)
					(thickness 0.15)
				)
				(justify left bottom)
			)
		)
		(fp_text user "License: Apache-2.0"
			(at -1.25 7.003 0)
			(layer "F.Fab")
			(effects
				(font
					(size 0.7 0.7)
					(thickness 0.15)
				)
				(justify left bottom)
			)
		)
		(pad "" smd circle
			(at 0 0)
			(size 1 1)
			(layers "F.Cu" "F.Mask")
			(solder_mask_margin 0.5)
			(clearance 0.5)
		)
	)
	(footprint "antmicro-footprints:QFN-11_2x2mm_P0.5mm"
		(layer "F.Cu")
		(at 119.15 104.1 90)
		(property "Reference" "U2"
			(at 2 -1.05 0)
			(unlocked yes)
			(layer "F.SilkS")
			(effects
				(font
					(size 0.7 0.7)
					(thickness 0.15)
				)
			)
		)
		(property "Value" "MP2386GG"
			(at -1.637158 2.644508 90)
			(unlocked yes)
			(layer "F.Fab")
			(effects
				(font
					(size 0.7 0.7)
					(thickness 0.15)
				)
				(justify left bottom)
			)
		)
		(property "Datasheet" "https://www.monolithicpower.com/en/documentview/productdocument/index/version/2/document_type/Datasheet/lang/en/sku/MP2386GG-Z/document_id/4066/"
			(at 0 0 90)
			(layer "F.Fab")
			(hide yes)
			(effects
				(font
					(size 1.27 1.27)
					(thickness 0.15)
				)
			)
		)
		(property "Description" "DC/DC converter"
			(at 0 0 90)
			(layer "F.Fab")
			(hide yes)
			(effects
				(font
					(size 1.27 1.27)
					(thickness 0.15)
				)
			)
		)
		(property "Manufacturer" "Monolithic Power Systems"
			(at 0 0 90)
			(unlocked yes)
			(layer "F.Fab")
			(hide yes)
			(effects
				(font
					(size 1 1)
					(thickness 0.15)
				)
			)
		)
		(property "MPN" "MP2386GG-P"
			(at 0 0 90)
			(unlocked yes)
			(layer "F.Fab")
			(hide yes)
			(effects
				(font
					(size 1 1)
					(thickness 0.15)
				)
			)
		)
		(property "License" "Apache-2.0"
			(at 0 0 90)
			(unlocked yes)
			(layer "F.Fab")
			(hide yes)
			(effects
				(font
					(size 1 1)
					(thickness 0.15)
				)
			)
		)
		(property "Author" "Antmicro"
			(at 0 0 90)
			(unlocked yes)
			(layer "F.Fab")
			(hide yes)
			(effects
				(font
					(size 1 1)
					(thickness 0.15)
				)
			)
		)
		(sheetname "/PD and TB DC-DC/")
		(sheetfile "PD_and_TB_DC_DC.kicad_sch")
		(attr smd)
		(fp_line
			(start 1.249 -1.25)
			(end 1.249 -0.951)
			(stroke
				(width 0.15)
				(type solid)
			)
			(layer "F.SilkS")
		)
		(fp_line
			(start 0.949 -1.25)
			(end 1.249 -1.25)
			(stroke
				(width 0.15)
				(type solid)
			)
			(layer "F.SilkS")
		)
		(fp_line
			(start -1.25 -0.951)
			(end -1.25 -1.25)
			(stroke
				(width 0.15)
				(type solid)
			)
			(layer "F.SilkS")
		)
		(fp_line
			(start 1.249 0.949)
			(end 1.249 1.249)
			(stroke
				(width 0.15)
				(type solid)
			)
			(layer "F.SilkS")
		)
		(fp_line
			(start 1.249 1.249)
			(end 0.949 1.249)
			(stroke
				(width 0.15)
				(type solid)
			)
			(layer "F.SilkS")
		)
		(fp_line
			(start -0.951 1.249)
			(end -1.25 1.249)
			(stroke
				(width 0.15)
				(type solid)
			)
			(layer "F.SilkS")
		)
		(fp_line
			(start -1.25 1.249)
			(end -1.25 0.949)
			(stroke
				(width 0.15)
				(type solid)
			)
			(layer "F.SilkS")
		)
		(fp_circle
			(center -1.7 -1.1)
			(end -1.649 -1.1)
			(stroke
				(width 0.15)
				(type solid)
			)
			(fill yes)
			(layer "F.SilkS")
		)
		(fp_rect
			(start -1.5 -1.5)
			(end 1.498 1.498)
			(stroke
				(width 0.05)
				(type solid)
			)
			(fill no)
			(layer "F.CrtYd")
		)
		(fp_line
			(start 1.1 -1.101)
			(end 1.1 1.1)
			(stroke
				(width 0.15)
				(type solid)
			)
			(layer "F.Fab")
		)
		(fp_line
			(start -0.552 -1.101)
			(end 1.1 -1.101)
			(stroke
				(width 0.15)
				(type solid)
			)
			(layer "F.Fab")
		)
		(fp_line
			(start -0.552 -1.101)
			(end -1.101 -0.552)
			(stroke
				(width 0.15)
				(type solid)
			)
			(layer "F.Fab")
		)
		(fp_line
			(start 1.1 1.1)
			(end -1.101 1.1)
			(stroke
				(width 0.15)
				(type solid)
			)
			(layer "F.Fab")
		)
		(fp_line
			(start -1.101 1.1)
			(end -1.101 -0.552)
			(stroke
				(width 0.15)
				(type solid)
			)
			(layer "F.Fab")
		)
		(fp_text user "License: Apache-2.0"
			(at -1.401 5.85 90)
			(layer "F.Fab")
			(effects
				(font
					(size 0.7 0.7)
					(thickness 0.15)
				)
				(justify left bottom)
			)
		)
		(fp_text user "${REFERENCE}"
			(at -1.401 3.45 90)
			(layer "F.Fab")
			(effects
				(font
					(size 0.7 0.7)
					(thickness 0.15)
				)
				(justify left bottom)
			)
		)
		(fp_text user "Author: Antmicro"
			(at -1.401 4.65 90)
			(layer "F.Fab")
			(effects
				(font
					(size 0.7 0.7)
					(thickness 0.15)
				)
				(justify left bottom)
			)
		)
		(pad "1" smd roundrect
			(at -0.552 -0.25 270)
			(size 1.5 0.25)
			(layers "F.Cu" "F.Mask" "F.Paste")
			(roundrect_rratio 0.25)
			(net 161 "Net-(U2-VIN)")
			(pinfunction "VIN")
			(pintype "power_in")
		)
		(pad "2" smd roundrect
			(at -0.75 0.998 180)
			(size 0.7 0.25)
			(layers "F.Cu" "F.Mask" "F.Paste")
			(roundrect_rratio 0.25)
			(net 23 "GND")
			(pinfunction "PGND")
			(pintype "power_in")
		)
		(pad "3" smd roundrect
			(at -0.25 0.998 180)
			(size 0.7 0.25)
			(layers "F.Cu" "F.Mask" "F.Paste")
			(roundrect_rratio 0.25)
			(net 23 "GND")
			(pinfunction "PGND")
			(pintype "passive")
		)
		(pad "4" smd roundrect
			(at 0.248 0.998 180)
			(size 0.7 0.25)
			(layers "F.Cu" "F.Mask" "F.Paste")
			(roundrect_rratio 0.25)
			(net 23 "GND")
			(pinfunction "PGND")
			(pintype "passive")
		)
		(pad "5" smd roundrect
			(at 0.748 0.998 180)
			(size 0.7 0.25)
			(layers "F.Cu" "F.Mask" "F.Paste")
			(roundrect_rratio 0.25)
			(net 17 "Net-(U2-PG)")
			(pinfunction "PG")
			(pintype "open_collector")
		)
		(pad "6" smd roundrect
			(at 0.55 0.2 270)
			(size 1.5 0.25)
			(layers "F.Cu" "F.Mask" "F.Paste")
			(roundrect_rratio 0.25)
			(net 163 "Net-(U2-SW)")
			(pinfunction "SW")
			(pintype "power_out")
		)
		(pad "7" smd roundrect
			(at 0.949 -0.25 270)
			(size 0.7 0.25)
			(layers "F.Cu" "F.Mask" "F.Paste")
			(roundrect_rratio 0.25)
			(net 162 "Net-(U2-BST)")
			(pinfunction "BST")
			(pintype "input")
		)
		(pad "8" smd roundrect
			(at 0.748 -1 180)
			(size 0.7 0.25)
			(layers "F.Cu" "F.Mask" "F.Paste")
			(roundrect_rratio 0.25)
			(net 303 "/PD and TB DC-DC/SMPS_LDO")
			(pinfunction "VCC")
			(pintype "power_out")
		)
		(pad "9" smd roundrect
			(at 0.248 -1 180)
			(size 0.7 0.25)
			(layers "F.Cu" "F.Mask" "F.Paste")
			(roundrect_rratio 0.25)
			(net 23 "GND")
			(pinfunction "AGND")
			(pintype "power_in")
		)
		(pad "10" smd roundrect
			(at -0.25 -1 180)
			(size 0.7 0.25)
			(layers "F.Cu" "F.Mask" "F.Paste")
			(roundrect_rratio 0.25)
			(net 166 "Net-(U2-FB)")
			(pinfunction "FB")
			(pintype "input")
		)
		(pad "11" smd roundrect
			(at -0.75 -1 180)
			(size 0.7 0.25)
			(layers "F.Cu" "F.Mask" "F.Paste")
			(roundrect_rratio 0.25)
			(net 413 "Net-(D3-C)")
			(pinfunction "EN")
			(pintype "input")
		)
	)
)
